# SCM (Grand Teton) — schematic netlist excerpt (pin names and nets, part order shuffled) for the footprints in the layout excerpt that follows; sources: Cadence DE-HDL packaged netlist, KiCad conversion of 12092022_DA0F0TMDCD0_F0T_Management_Board_D_brd_V3_OCP.brd

R314  Q_RES  100K 1% CHIP  pkg 0402LF  page 22 : A = RST_BMC_SELF_HW_D_C ; B = GND

U28  74LVC1G66GV  IC  pkg SC74AXA  page 13
  Y  = RMII_OCP_RCLKI
  Z  = RMII_OCP_RCLKI_ISO
  GND  = GND
  E  = PWRGD_P1V0_AUX_DELAY_R
  VCC  = P3V3_LDO

(kicad_pcb
	(version 20260206)
	(generator "pcbnew")
	(generator_version "10.0")
	(general
		(thickness 1.6)
		(legacy_teardrops no)
	)
	(paper "A4")
	(title_block
		(title "12092022_DA0F0TMDCD0_F0T_Management_Board_D_brd_V3_OCP.brd")
		(comment 1 "Grand Teton / footprints 671-672 of 1440")
	)
	(layers
		(0 "F.Cu" signal "TOP")
		(4 "In1.Cu" signal "GND")
		(6 "In2.Cu" signal "IN1")
		(8 "In3.Cu" signal "GND1")
		(10 "In4.Cu" signal "IN2")
		(12 "In5.Cu" signal "VCC")
		(14 "In6.Cu" signal "VCC1")
		(16 "In7.Cu" signal "IN3")
		(18 "In8.Cu" signal "GND2")
		(20 "In9.Cu" signal "IN4")
		(22 "In10.Cu" signal "GND3")
		(2 "B.Cu" signal "BOTTOM")
		(9 "F.Adhes" user "F.Adhesive")
		(11 "B.Adhes" user "B.Adhesive")
		(13 "F.Paste" user "Package Geometry/Pastemask Top")
		(15 "B.Paste" user "Package Geometry/Pastemask Bottom")
		(5 "F.SilkS" user "Ref Des/Silkscreen Top")
		(7 "B.SilkS" user "Ref Des/Silkscreen Bottom")
		(1 "F.Mask" user "Board Geometry/Soldermask Top")
		(3 "B.Mask" user "Board Geometry/Soldermask Bottom")
		(17 "Dwgs.User" user "User.Drawings")
		(19 "Cmts.User" user "User.Comments")
		(21 "Eco1.User" user "User.Eco1")
		(23 "Eco2.User" user "User.Eco2")
		(25 "Edge.Cuts" user "Board Geometry/Outline")
		(27 "Margin" user)
		(31 "F.CrtYd" user "Package Geometry/Place Bound Top")
		(29 "B.CrtYd" user "Package Geometry/Place Bound Bottom")
		(35 "F.Fab" user "Ref Des/Assembly Top")
		(33 "B.Fab" user "Ref Des/Assembly Bottom")
	)
	(footprint ""
		(layer "F.Cu")
		(at 23.1775 -105.918)
		(property "Reference" "R314"
			(at 0 0 0)
			(layer "F.SilkS")
			(hide yes)
			(effects
				(font
					(size 1.27 1.27)
				)
			)
		)
		(property "Value" ""
			(at 0 0 0)
			(layer "F.Fab")
			(effects
				(font
					(size 1.27 1.27)
				)
			)
		)
		(duplicate_pad_numbers_are_jumpers no)
		(fp_line
			(start -0.7874 -0.4064)
			(end 0.7874 -0.4064)
			(stroke
				(width 0.1524)
				(type default)
			)
			(layer "F.SilkS")
		)
		(fp_line
			(start -0.7874 0.4064)
			(end -0.7874 -0.4064)
			(stroke
				(width 0.1524)
				(type default)
			)
			(layer "F.SilkS")
		)
		(fp_line
			(start 0.7874 -0.4064)
			(end 0.7874 0.4064)
			(stroke
				(width 0.1524)
				(type default)
			)
			(layer "F.SilkS")
		)
		(fp_line
			(start 0.7874 0.4064)
			(end -0.7874 0.4064)
			(stroke
				(width 0.1524)
				(type default)
			)
			(layer "F.SilkS")
		)
		(fp_line
			(start -0.67945 -0.305054)
			(end -0.12065 -0.305054)
			(stroke
				(width 0.1)
				(type default)
			)
			(layer "F.Fab")
		)
		(fp_line
			(start -0.67945 0.3048)
			(end -0.67945 -0.305054)
			(stroke
				(width 0.1)
				(type default)
			)
			(layer "F.Fab")
		)
		(fp_line
			(start -0.12065 -0.305054)
			(end -0.12065 -0.2794)
			(stroke
				(width 0.1)
				(type default)
			)
			(layer "F.Fab")
		)
		(fp_line
			(start -0.12065 -0.2794)
			(end 0.12065 -0.2794)
			(stroke
				(width 0.1)
				(type default)
			)
			(layer "F.Fab")
		)
		(fp_line
			(start -0.12065 0.2794)
			(end -0.12065 0.3048)
			(stroke
				(width 0.1)
				(type default)
			)
			(layer "F.Fab")
		)
		(fp_line
			(start -0.12065 0.3048)
			(end -0.67945 0.3048)
			(stroke
				(width 0.1)
				(type default)
			)
			(layer "F.Fab")
		)
		(fp_line
			(start 0.120396 0.2794)
			(end -0.12065 0.2794)
			(stroke
				(width 0.1)
				(type default)
			)
			(layer "F.Fab")
		)
		(fp_line
			(start 0.120396 0.3048)
			(end 0.120396 0.2794)
			(stroke
				(width 0.1)
				(type default)
			)
			(layer "F.Fab")
		)
		(fp_line
			(start 0.12065 -0.3048)
			(end 0.67945 -0.3048)
			(stroke
				(width 0.1)
				(type default)
			)
			(layer "F.Fab")
		)
		(fp_line
			(start 0.12065 -0.2794)
			(end 0.12065 -0.3048)
			(stroke
				(width 0.1)
				(type default)
			)
			(layer "F.Fab")
		)
		(fp_line
			(start 0.67945 -0.3048)
			(end 0.67945 0.3048)
			(stroke
				(width 0.1)
				(type default)
			)
			(layer "F.Fab")
		)
		(fp_line
			(start 0.67945 0.3048)
			(end 0.120396 0.3048)
			(stroke
				(width 0.1)
				(type default)
			)
			(layer "F.Fab")
		)
		(pad "1" smd circle
			(at -0.40005 0)
			(size 0 0)
			(layers "F.Cu" "F.Mask" "F.Paste")
			(net "RST_BMC_SELF_HW_D_C")
		)
		(pad "2" smd circle
			(at 0.40005 0)
			(size 0 0)
			(layers "F.Cu" "F.Mask" "F.Paste")
			(net "GND")
		)
	)
	(footprint ""
		(layer "F.Cu")
		(at 42.3418 -26.2636)
		(property "Reference" "U28"
			(at 0.573278 -2.323846 0)
			(unlocked yes)
			(layer "F.SilkS")
			(effects
				(font
					(size 0.7874 0.5842)
					(thickness 0.1524)
				)
				(justify left)
			)
		)
		(property "Value" ""
			(at 0 0 0)
			(layer "F.Fab")
			(effects
				(font
					(size 1.27 1.27)
				)
			)
		)
		(duplicate_pad_numbers_are_jumpers no)
		(fp_line
			(start -2.032 -1.549908)
			(end 2.032 -1.549908)
			(stroke
				(width 0.1524)
				(type default)
			)
			(layer "F.SilkS")
		)
		(fp_line
			(start -2.032 1.549908)
			(end -2.032 -1.549908)
			(stroke
				(width 0.1524)
				(type default)
			)
			(layer "F.SilkS")
		)
		(fp_line
			(start 2.032 -1.549908)
			(end 2.032 1.549908)
			(stroke
				(width 0.1524)
				(type default)
			)
			(layer "F.SilkS")
		)
		(fp_line
			(start 2.032 1.549908)
			(end -2.032 1.549908)
			(stroke
				(width 0.1524)
				(type default)
			)
			(layer "F.SilkS")
		)
		(fp_poly
			(pts
				(xy -2.9464 -1.2192) (xy -2.9464 -0.7112) (xy -2.1844 -0.9652)
			)
			(stroke
				(width 0)
				(type default)
			)
			(fill yes)
			(layer "F.SilkS")
		)
		(fp_line
			(start -0.849884 -1.549908)
			(end -0.849884 1.549908)
			(stroke
				(width 0.1)
				(type default)
			)
			(layer "F.Fab")
		)
		(fp_line
			(start -0.849884 1.549908)
			(end 0.849884 1.549908)
			(stroke
				(width 0.1)
				(type default)
			)
			(layer "F.Fab")
		)
		(fp_line
			(start 0.849884 -1.549908)
			(end -0.849884 -1.549908)
			(stroke
				(width 0.1)
				(type default)
			)
			(layer "F.Fab")
		)
		(fp_line
			(start 0.849884 1.549908)
			(end 0.849884 -1.549908)
			(stroke
				(width 0.1)
				(type default)
			)
			(layer "F.Fab")
		)
		(fp_poly
			(pts
				(xy -2.9464 -1.2192) (xy -2.9464 -0.7112) (xy -2.1844 -0.9652)
			)
			(stroke
				(width 0)
				(type default)
			)
			(fill yes)
			(layer "F.Fab")
		)
		(pad "1" smd rect
			(at -1.225042 -0.94996 270)
			(size 0.4572 1.3208)
			(layers "F.Cu" "F.Mask" "F.Paste")
			(net "RMII_OCP_RCLKI")
		)
		(pad "2" smd rect
			(at -1.225042 0 270)
			(size 0.4572 1.3208)
			(layers "F.Cu" "F.Mask" "F.Paste")
			(net "RMII_OCP_RCLKI_ISO")
		)
		(pad "3" smd rect
			(at -1.225042 0.94996 270)
			(size 0.4572 1.3208)
			(layers "F.Cu" "F.Mask" "F.Paste")
			(net "GND")
		)
		(pad "4" smd rect
			(at 1.225042 0.94996 270)
			(size 0.4572 1.3208)
			(layers "F.Cu" "F.Mask" "F.Paste")
			(net "PWRGD_P1V0_AUX_DELAY_R")
		)
		(pad "5" smd rect
			(at 1.225042 -0.94996 270)
			(size 0.4572 1.3208)
			(layers "F.Cu" "F.Mask" "F.Paste")
			(net "P3V3_LDO")
		)
	)
)
